(kicad_pcb
	(version 20221018)
	(generator pcbnew)
	(general
    (thickness 1.562)
  )
	(paper "A4")
	(title_block
    (title "Thunderbolt PCIe Adaper")
    (date "2024-07-09")
    (rev "1.0.3")
    (comment 1 "www.antmicro.com")
    (comment 2 "Antmicro Ltd.")
		(comment 9 "footprints 245-253 of 271")
	)
	(layers
    (0 "F.Cu" signal)
    (1 "In1.Cu" signal)
    (2 "In2.Cu" signal)
    (3 "In3.Cu" signal)
    (4 "In4.Cu" signal)
    (31 "B.Cu" signal)
    (32 "B.Adhes" user "B.Adhesive")
    (33 "F.Adhes" user "F.Adhesive")
    (34 "B.Paste" user)
    (35 "F.Paste" user)
    (36 "B.SilkS" user "B.Silkscreen")
    (37 "F.SilkS" user "F.Silkscreen")
    (38 "B.Mask" user)
    (39 "F.Mask" user)
    (40 "Dwgs.User" user "User.Drawings")
    (41 "Cmts.User" user "User.Comments")
    (42 "Eco1.User" user "User.Eco1")
    (43 "Eco2.User" user "User.Eco2")
    (44 "Edge.Cuts" user)
    (45 "Margin" user)
    (46 "B.CrtYd" user "B.Courtyard")
    (47 "F.CrtYd" user "F.Courtyard")
    (48 "B.Fab" user)
    (49 "F.Fab" user)
  )
	(footprint "antmicro-footprints:C_0402_1005Metric" (layer "B.Cu")
    (at 132.85 82.125)
    (descr "Capacitor SMD 0402")
    (tags "capacitor SMD 0402")
    (property "Author" "Antmicro")
    (property "Dielectric" "")
    (property "License" "Apache-2.0")
    (property "MPN" "C1005X6S1A105K050BC")
    (property "Manufacturer" "TDK")
    (property "Sheetfile" "tb-power.kicad_sch")
    (property "Sheetname" "Thunderbolt Controller - Power")
    (property "Val" "1u")
    (property "Voltage" "")
    (property "ki_description" "SMD Multilayer Ceramic Capacitor, 1 µF, 10 V, 0402 [1005 Metric], ± 10%, X6S, C")
    (property "ki_keywords" "0402, SMT, CAPACITOR, PASSIVE, CERAMIC, MLCC")
    (attr smd)
    (fp_text reference "C51" (at 17.518 7.41 180) (layer "B.SilkS")
        (effects (font (size 0.7 0.7) (thickness 0.15)) (justify left bottom mirror))
    )
    (fp_text value "C_1u_0402" (at -1.022927 -2.155213 180) (layer "B.Fab")
        (effects (font (size 0.7 0.7) (thickness 0.15)) (justify left bottom mirror))
    )
    (fp_text user "Author: Antmicro" (at -0.939 -3.399 180) (layer "B.Fab") hide
        (effects (font (size 0.7 0.7) (thickness 0.15)) (justify left bottom mirror))
    )
    (fp_text user "License: Apache-2.0" (at -0.939 -5.799 180) (layer "B.Fab") hide
        (effects (font (size 0.7 0.7) (thickness 0.15)) (justify left bottom mirror))
    )
    (fp_text user "${REFERENCE}" (at -0.939 -4.599 180) (layer "B.Fab") hide
        (effects (font (size 0.7 0.7) (thickness 0.15)) (justify left bottom mirror))
    )
    (fp_rect (start -0.925 0.47) (end 0.925 -0.47)
      (stroke (width 0.05) (type default)) (fill none) (layer "B.CrtYd"))
    (fp_line (start -0.494 -0.248) (end -0.494 0.25)
      (stroke (width 0.15) (type solid)) (layer "B.Fab"))
    (fp_line (start -0.494 0.25) (end 0.504 0.25)
      (stroke (width 0.15) (type solid)) (layer "B.Fab"))
    (fp_line (start 0.504 -0.248) (end -0.494 -0.248)
      (stroke (width 0.15) (type solid)) (layer "B.Fab"))
    (fp_line (start 0.504 0.25) (end 0.504 -0.248)
      (stroke (width 0.15) (type solid)) (layer "B.Fab"))
    (pad "1" smd roundrect (at -0.48 0) (size 0.59 0.64) (layers "B.Cu" "B.Paste" "B.Mask") (roundrect_rratio 0.25)
      (net 1 "GND") (pintype "passive"))
    (pad "2" smd roundrect (at 0.48 0) (size 0.59 0.64) (layers "B.Cu" "B.Paste" "B.Mask") (roundrect_rratio 0.25)
      (net 105 "Net-(C51-Pad2)") (pintype "passive"))
  )
	(footprint "antmicro-footprints:R_0402_1005Metric" (layer "B.Cu")
    (at 131.075 66.82 -90)
    (descr "Resistor SMD 0402")
    (tags "resistor SMD 0402")
    (property "Author" "Antmicro")
    (property "License" "Apache-2.0")
    (property "MPN" "CR0402-FX-2201GLF")
    (property "Manufacturer" "Bourns")
    (property "Sheetfile" "tb.kicad_sch")
    (property "Sheetname" "TB Controller")
    (property "Tolerance" "1%")
    (property "Val" "2k2")
    (property "ki_description" "SMD Chip Resistor, 2.2 kohm, ± 1%, 62.5 mW, 0402 [1005 Metric], Thick Film, General Purpose")
    (property "ki_keywords" "0402, SMT, RESISTOR, PASSIVE")
    (attr smd)
    (fp_text reference "R58" (at -3.066 -0.325 90) (layer "B.SilkS")
        (effects (font (size 0.7 0.7) (thickness 0.15)) (justify left bottom mirror))
    )
    (fp_text value "R_2k2_0402" (at -1.011843 -1.772047 90) (layer "B.Fab")
        (effects (font (size 0.7 0.7) (thickness 0.15)) (justify left bottom mirror))
    )
    (fp_text user "Author: Antmicro" (at -0.95 -4.169 90) (layer "B.Fab") hide
        (effects (font (size 0.7 0.7) (thickness 0.15)) (justify left bottom mirror))
    )
    (fp_text user "${REFERENCE}" (at -0.95 -3.168 90) (layer "B.Fab") hide
        (effects (font (size 0.7 0.7) (thickness 0.15)) (justify left bottom mirror))
    )
    (fp_text user "License: Apache-2.0" (at -0.95 -5.169 90) (layer "B.Fab") hide
        (effects (font (size 0.7 0.7) (thickness 0.15)) (justify left bottom mirror))
    )
    (fp_rect (start -0.925 0.47) (end 0.925 -0.47)
      (stroke (width 0.05) (type default)) (fill none) (layer "B.CrtYd"))
    (fp_rect (start -0.5 0.25) (end 0.5 -0.25)
      (stroke (width 0.15) (type solid)) (fill none) (layer "B.Fab"))
    (pad "1" smd roundrect (at -0.48 0 270) (size 0.59 0.64) (layers "B.Cu" "B.Paste" "B.Mask") (roundrect_rratio 0.25)
      (net 1 "GND") (pintype "passive"))
    (pad "2" smd roundrect (at 0.48 0 270) (size 0.59 0.64) (layers "B.Cu" "B.Paste" "B.Mask") (roundrect_rratio 0.25)
      (net 172 "Net-(U4C-DPSNK0_DDC_CLK)") (pintype "passive"))
  )
	(footprint "antmicro-footprints:C_0402_1005Metric" (layer "B.Cu")
    (at 137.225 81.3 90)
    (descr "Capacitor SMD 0402")
    (tags "capacitor SMD 0402")
    (property "Author" "Antmicro")
    (property "Dielectric" "")
    (property "License" "Apache-2.0")
    (property "MPN" "C1005X6S1A105K050BC")
    (property "Manufacturer" "TDK")
    (property "Sheetfile" "tb-power.kicad_sch")
    (property "Sheetname" "Thunderbolt Controller - Power")
    (property "Val" "1u")
    (property "Voltage" "")
    (property "ki_description" "SMD Multilayer Ceramic Capacitor, 1 µF, 10 V, 0402 [1005 Metric], ± 10%, X6S, C")
    (property "ki_keywords" "0402, SMT, CAPACITOR, PASSIVE, CERAMIC, MLCC")
    (attr smd)
    (fp_text reference "C87" (at -6.584 16.953 270) (layer "B.SilkS")
        (effects (font (size 0.7 0.7) (thickness 0.15)) (justify left bottom mirror))
    )
    (fp_text value "C_1u_0402" (at -1.022927 -2.155213 270) (layer "B.Fab")
        (effects (font (size 0.7 0.7) (thickness 0.15)) (justify left bottom mirror))
    )
    (fp_text user "${REFERENCE}" (at -0.939 -4.599 270) (layer "B.Fab") hide
        (effects (font (size 0.7 0.7) (thickness 0.15)) (justify left bottom mirror))
    )
    (fp_text user "Author: Antmicro" (at -0.939 -3.399 270) (layer "B.Fab") hide
        (effects (font (size 0.7 0.7) (thickness 0.15)) (justify left bottom mirror))
    )
    (fp_text user "License: Apache-2.0" (at -0.939 -5.799 270) (layer "B.Fab") hide
        (effects (font (size 0.7 0.7) (thickness 0.15)) (justify left bottom mirror))
    )
    (fp_rect (start -0.925 0.47) (end 0.925 -0.47)
      (stroke (width 0.05) (type default)) (fill none) (layer "B.CrtYd"))
    (fp_line (start -0.494 -0.248) (end -0.494 0.25)
      (stroke (width 0.15) (type solid)) (layer "B.Fab"))
    (fp_line (start -0.494 0.25) (end 0.504 0.25)
      (stroke (width 0.15) (type solid)) (layer "B.Fab"))
    (fp_line (start 0.504 -0.248) (end -0.494 -0.248)
      (stroke (width 0.15) (type solid)) (layer "B.Fab"))
    (fp_line (start 0.504 0.25) (end 0.504 -0.248)
      (stroke (width 0.15) (type solid)) (layer "B.Fab"))
    (pad "1" smd roundrect (at -0.48 0 90) (size 0.59 0.64) (layers "B.Cu" "B.Paste" "B.Mask") (roundrect_rratio 0.25)
      (net 1 "GND") (pintype "passive"))
    (pad "2" smd roundrect (at 0.48 0 90) (size 0.59 0.64) (layers "B.Cu" "B.Paste" "B.Mask") (roundrect_rratio 0.25)
      (net 112 "Net-(U4A-VCC0P9_SVR_SENSE)") (pintype "passive"))
  )
	(footprint "antmicro-footprints:C_0402_1005Metric" (layer "B.Cu")
    (at 137.725 79.85 180)
    (descr "Capacitor SMD 0402")
    (tags "capacitor SMD 0402")
    (property "Author" "Antmicro")
    (property "Dielectric" "")
    (property "License" "Apache-2.0")
    (property "MPN" "C1005X6S1A105K050BC")
    (property "Manufacturer" "TDK")
    (property "Sheetfile" "tb-power.kicad_sch")
    (property "Sheetname" "Thunderbolt Controller - Power")
    (property "Val" "1u")
    (property "Voltage" "")
    (property "ki_description" "SMD Multilayer Ceramic Capacitor, 1 µF, 10 V, 0402 [1005 Metric], ± 10%, X6S, C")
    (property "ki_keywords" "0402, SMT, CAPACITOR, PASSIVE, CERAMIC, MLCC")
    (attr smd)
    (fp_text reference "C85" (at -17.596 -8.034) (layer "B.SilkS")
        (effects (font (size 0.7 0.7) (thickness 0.15)) (justify left bottom mirror))
    )
    (fp_text value "C_1u_0402" (at -1.022927 -2.155213) (layer "B.Fab")
        (effects (font (size 0.7 0.7) (thickness 0.15)) (justify left bottom mirror))
    )
    (fp_text user "License: Apache-2.0" (at -0.939 -5.799) (layer "B.Fab") hide
        (effects (font (size 0.7 0.7) (thickness 0.15)) (justify left bottom mirror))
    )
    (fp_text user "${REFERENCE}" (at -0.939 -4.599) (layer "B.Fab") hide
        (effects (font (size 0.7 0.7) (thickness 0.15)) (justify left bottom mirror))
    )
    (fp_text user "Author: Antmicro" (at -0.939 -3.399) (layer "B.Fab") hide
        (effects (font (size 0.7 0.7) (thickness 0.15)) (justify left bottom mirror))
    )
    (fp_rect (start -0.925 0.47) (end 0.925 -0.47)
      (stroke (width 0.05) (type default)) (fill none) (layer "B.CrtYd"))
    (fp_line (start -0.494 -0.248) (end -0.494 0.25)
      (stroke (width 0.15) (type solid)) (layer "B.Fab"))
    (fp_line (start -0.494 0.25) (end 0.504 0.25)
      (stroke (width 0.15) (type solid)) (layer "B.Fab"))
    (fp_line (start 0.504 -0.248) (end -0.494 -0.248)
      (stroke (width 0.15) (type solid)) (layer "B.Fab"))
    (fp_line (start 0.504 0.25) (end 0.504 -0.248)
      (stroke (width 0.15) (type solid)) (layer "B.Fab"))
    (pad "1" smd roundrect (at -0.48 0 180) (size 0.59 0.64) (layers "B.Cu" "B.Paste" "B.Mask") (roundrect_rratio 0.25)
      (net 1 "GND") (pintype "passive"))
    (pad "2" smd roundrect (at 0.48 0 180) (size 0.59 0.64) (layers "B.Cu" "B.Paste" "B.Mask") (roundrect_rratio 0.25)
      (net 113 "Net-(U4A-VCC0P9_LVR_SENSE)") (pintype "passive"))
  )
	(footprint "antmicro-footprints:R_0402_1005Metric" (layer "B.Cu")
    (at 142.17 78.385 90)
    (descr "Resistor SMD 0402")
    (tags "resistor SMD 0402")
    (property "Author" "Antmicro")
    (property "License" "Apache-2.0")
    (property "MPN" "CR0402-FX-4990GLF")
    (property "Manufacturer" "Bourns")
    (property "Sheetfile" "tb.kicad_sch")
    (property "Sheetname" "TB Controller")
    (property "Tolerance" "1%")
    (property "Val" "499R")
    (property "ki_description" "SMD Chip Resistor, 499 ohm, ± 1%, 63 mW, 0402 [1005 Metric], Thick Film, General Purpose")
    (property "ki_keywords" "0402, SMT, RESISTOR, PASSIVE")
    (attr smd)
    (fp_text reference "R73" (at -0.99 0.451 270) (layer "B.SilkS")
        (effects (font (size 0.7 0.7) (thickness 0.15)) (justify left bottom mirror))
    )
    (fp_text value "R_499R_0402" (at -1.011843 -1.772047 270) (layer "B.Fab")
        (effects (font (size 0.7 0.7) (thickness 0.15)) (justify left bottom mirror))
    )
    (fp_text user "License: Apache-2.0" (at -0.95 -5.169 270) (layer "B.Fab") hide
        (effects (font (size 0.7 0.7) (thickness 0.15)) (justify left bottom mirror))
    )
    (fp_text user "Author: Antmicro" (at -0.95 -4.169 270) (layer "B.Fab") hide
        (effects (font (size 0.7 0.7) (thickness 0.15)) (justify left bottom mirror))
    )
    (fp_text user "${REFERENCE}" (at -0.95 -3.168 270) (layer "B.Fab") hide
        (effects (font (size 0.7 0.7) (thickness 0.15)) (justify left bottom mirror))
    )
    (fp_rect (start -0.925 0.47) (end 0.925 -0.47)
      (stroke (width 0.05) (type default)) (fill none) (layer "B.CrtYd"))
    (fp_rect (start -0.5 0.25) (end 0.5 -0.25)
      (stroke (width 0.15) (type solid)) (fill none) (layer "B.Fab"))
    (pad "1" smd roundrect (at -0.48 0 90) (size 0.59 0.64) (layers "B.Cu" "B.Paste" "B.Mask") (roundrect_rratio 0.25)
      (net 188 "Net-(U4E-PB_USB2_RBIAS)") (pintype "passive"))
    (pad "2" smd roundrect (at 0.48 0 90) (size 0.59 0.64) (layers "B.Cu" "B.Paste" "B.Mask") (roundrect_rratio 0.25)
      (net 1 "GND") (pintype "passive"))
  )
	(footprint "antmicro-footprints:Fiducial_1mm_Mask3mm" (layer "B.Cu")
    (at 168 59 180)
    (descr "Circular Fiducial, 1.5mm bare copper, 3mm soldermask opening")
    (tags "fiducial")
    (property "Author" "Antmicro")
    (property "License" "Apache-2.0")
    (property "Sheetfile" "thunderbolt-pcie-adapter.kicad_sch")
    (property "Sheetname" "")
    (property "exclude_from_bom" "")
    (property "ki_description" "Fiducial mask")
    (attr through_hole exclude_from_bom)
    (fp_text reference "FID7" (at -1.291 -2.595) (layer "B.SilkS")
        (effects (font (size 0.7 0.7) (thickness 0.15)) (justify left bottom mirror))
    )
    (fp_text value "Fiducial_1mm_Mask3mm" (at 0 -2.603) (layer "B.Fab")
        (effects (font (size 0.7 0.7) (thickness 0.15)) (justify left bottom mirror))
    )
    (fp_text user "${REFERENCE}" (at -1.25 -4.603) (layer "B.Fab") hide
        (effects (font (size 0.7 0.7) (thickness 0.15)) (justify left bottom mirror))
    )
    (fp_text user "License: Apache-2.0" (at -1.25 -7.003) (layer "B.Fab") hide
        (effects (font (size 0.7 0.7) (thickness 0.15)) (justify left bottom mirror))
    )
    (fp_text user "Author: Antmicro" (at -1.25 -5.803) (layer "B.Fab") hide
        (effects (font (size 0.7 0.7) (thickness 0.15)) (justify left bottom mirror))
    )
    (fp_circle (center 0 0) (end 1.5 0)
      (stroke (width 0.05) (type solid)) (fill none) (layer "B.CrtYd"))
    (fp_circle (center 0 0) (end 1.5 0)
      (stroke (width 0.15) (type solid)) (fill none) (layer "B.Fab"))
    (pad "" smd circle (at 0 0 180) (size 1 1) (layers "B.Cu" "B.Mask")
      (solder_mask_margin 1) (clearance 1))
  )
	(footprint "antmicro-footprints:R_0402_1005Metric" (layer "B.Cu")
    (at 145.62 73.96 180)
    (descr "Resistor SMD 0402")
    (tags "resistor SMD 0402")
    (property "Author" "Antmicro")
    (property "License" "Apache-2.0")
    (property "MPN" "CR0402-FX-1004GLF")
    (property "Manufacturer" "Bourns")
    (property "Sheetfile" "tb.kicad_sch")
    (property "Sheetname" "TB Controller")
    (property "Tolerance" "1%")
    (property "Val" "1M")
    (property "ki_description" "SMD Chip Resistor, 1 Mohm, ± 1%, 62.5 mW, 0402 [1005 Metric], Thick Film, General Purpose")
    (property "ki_keywords" "0402, SMT, RESISTOR, PASSIVE")
    (attr smd)
    (fp_text reference "R70" (at -3.097 -0.462) (layer "B.SilkS")
        (effects (font (size 0.7 0.7) (thickness 0.15)) (justify left bottom mirror))
    )
    (fp_text value "R_1M_0402" (at -1.011843 -1.772047) (layer "B.Fab")
        (effects (font (size 0.7 0.7) (thickness 0.15)) (justify left bottom mirror))
    )
    (fp_text user "${REFERENCE}" (at -0.95 -3.168) (layer "B.Fab") hide
        (effects (font (size 0.7 0.7) (thickness 0.15)) (justify left bottom mirror))
    )
    (fp_text user "Author: Antmicro" (at -0.95 -4.169) (layer "B.Fab") hide
        (effects (font (size 0.7 0.7) (thickness 0.15)) (justify left bottom mirror))
    )
    (fp_text user "License: Apache-2.0" (at -0.95 -5.169) (layer "B.Fab") hide
        (effects (font (size 0.7 0.7) (thickness 0.15)) (justify left bottom mirror))
    )
    (fp_rect (start -0.925 0.47) (end 0.925 -0.47)
      (stroke (width 0.05) (type default)) (fill none) (layer "B.CrtYd"))
    (fp_rect (start -0.5 0.25) (end 0.5 -0.25)
      (stroke (width 0.15) (type solid)) (fill none) (layer "B.Fab"))
    (pad "1" smd roundrect (at -0.48 0 180) (size 0.59 0.64) (layers "B.Cu" "B.Paste" "B.Mask") (roundrect_rratio 0.25)
      (net 185 "Net-(U4E-PB_LSTX)") (pintype "passive"))
    (pad "2" smd roundrect (at 0.48 0 180) (size 0.59 0.64) (layers "B.Cu" "B.Paste" "B.Mask") (roundrect_rratio 0.25)
      (net 1 "GND") (pintype "passive"))
  )
	(footprint "antmicro-footprints:R_0402_1005Metric" (layer "B.Cu")
    (at 151.41 60.97)
    (descr "Resistor SMD 0402")
    (tags "resistor SMD 0402")
    (property "Author" "Antmicro")
    (property "License" "Apache-2.0")
    (property "MPN" "CR0402-FX-2201GLF")
    (property "Manufacturer" "Bourns")
    (property "Sheetfile" "power.kicad_sch")
    (property "Sheetname" "Power")
    (property "Tolerance" "1%")
    (property "Val" "2k2")
    (property "ki_description" "SMD Chip Resistor, 2.2 kohm, ± 1%, 62.5 mW, 0402 [1005 Metric], Thick Film, General Purpose")
    (property "ki_keywords" "0402, SMT, RESISTOR, PASSIVE")
    (attr smd)
    (fp_text reference "R3" (at -0.915 0.482 180) (layer "B.SilkS")
        (effects (font (size 0.7 0.7) (thickness 0.15)) (justify left bottom mirror))
    )
    (fp_text value "R_2k2_0402" (at -1.011843 -1.772047 180) (layer "B.Fab")
        (effects (font (size 0.7 0.7) (thickness 0.15)) (justify left bottom mirror))
    )
    (fp_text user "License: Apache-2.0" (at -0.95 -5.169 180) (layer "B.Fab") hide
        (effects (font (size 0.7 0.7) (thickness 0.15)) (justify left bottom mirror))
    )
    (fp_text user "${REFERENCE}" (at -0.95 -3.168 180) (layer "B.Fab") hide
        (effects (font (size 0.7 0.7) (thickness 0.15)) (justify left bottom mirror))
    )
    (fp_text user "Author: Antmicro" (at -0.95 -4.169 180) (layer "B.Fab") hide
        (effects (font (size 0.7 0.7) (thickness 0.15)) (justify left bottom mirror))
    )
    (fp_rect (start -0.925 0.47) (end 0.925 -0.47)
      (stroke (width 0.05) (type default)) (fill none) (layer "B.CrtYd"))
    (fp_rect (start -0.5 0.25) (end 0.5 -0.25)
      (stroke (width 0.15) (type solid)) (fill none) (layer "B.Fab"))
    (pad "1" smd roundrect (at -0.48 0) (size 0.59 0.64) (layers "B.Cu" "B.Paste" "B.Mask") (roundrect_rratio 0.25)
      (net 57 "I2C1_SCL") (pintype "passive"))
    (pad "2" smd roundrect (at 0.48 0) (size 0.59 0.64) (layers "B.Cu" "B.Paste" "B.Mask") (roundrect_rratio 0.25)
      (net 2 "3V3_SYS") (pintype "passive"))
  )
	(footprint "antmicro-footprints:C_0402_1005Metric" (layer "B.Cu")
    (at 153.41 62.97 180)
    (descr "Capacitor SMD 0402")
    (tags "capacitor SMD 0402")
    (property "Author" "Antmicro")
    (property "Dielectric" "")
    (property "License" "Apache-2.0")
    (property "MPN" "CC0402MRX5R5BB106")
    (property "Manufacturer" "YAGEO")
    (property "Sheetfile" "power.kicad_sch")
    (property "Sheetname" "Power")
    (property "Val" "10u")
    (property "Voltage" "")
    (property "ki_description" "SMD Multilayer Ceramic Capacitor, 10 µF, 6.3 V, 0402 [1005 Metric], ± 20%, X5R, CC Series")
    (property "ki_keywords" "0402, SMT, CAPACITOR, PASSIVE, MLCC, CERAMIC")
    (attr smd)
    (fp_text reference "C39" (at -0.768 -4.467) (layer "B.SilkS")
        (effects (font (size 0.7 0.7) (thickness 0.15)) (justify left bottom mirror))
    )
    (fp_text value "C_10u_0402" (at -1.022927 -2.155213) (layer "B.Fab")
        (effects (font (size 0.7 0.7) (thickness 0.15)) (justify left bottom mirror))
    )
    (fp_text user "Author: Antmicro" (at -0.939 -3.399) (layer "B.Fab") hide
        (effects (font (size 0.7 0.7) (thickness 0.15)) (justify left bottom mirror))
    )
    (fp_text user "${REFERENCE}" (at -0.939 -4.599) (layer "B.Fab") hide
        (effects (font (size 0.7 0.7) (thickness 0.15)) (justify left bottom mirror))
    )
    (fp_text user "License: Apache-2.0" (at -0.939 -5.799) (layer "B.Fab") hide
        (effects (font (size 0.7 0.7) (thickness 0.15)) (justify left bottom mirror))
    )
    (fp_rect (start -0.925 0.47) (end 0.925 -0.47)
      (stroke (width 0.05) (type default)) (fill none) (layer "B.CrtYd"))
    (fp_line (start -0.494 -0.248) (end -0.494 0.25)
      (stroke (width 0.15) (type solid)) (layer "B.Fab"))
    (fp_line (start -0.494 0.25) (end 0.504 0.25)
      (stroke (width 0.15) (type solid)) (layer "B.Fab"))
    (fp_line (start 0.504 -0.248) (end -0.494 -0.248)
      (stroke (width 0.15) (type solid)) (layer "B.Fab"))
    (fp_line (start 0.504 0.25) (end 0.504 -0.248)
      (stroke (width 0.15) (type solid)) (layer "B.Fab"))
    (pad "1" smd roundrect (at -0.48 0 180) (size 0.59 0.64) (layers "B.Cu" "B.Paste" "B.Mask") (roundrect_rratio 0.25)
      (net 9 "/Power/TPS_3V3") (pintype "passive"))
    (pad "2" smd roundrect (at 0.48 0 180) (size 0.59 0.64) (layers "B.Cu" "B.Paste" "B.Mask") (roundrect_rratio 0.25)
      (net 1 "GND") (pintype "passive"))
  )
)
